(kicad_pcb
	(version 20260206)
	(generator "pcbnew")
	(generator_version "10.0")
	(general
		(thickness 1.6)
		(legacy_teardrops no)
	)
	(paper "A4")
	(title_block
		(title "pdpb — Lightning_PDPB_BRD.brd")
		(comment 1 "Lightning (Wiwynn / Facebook NVMe JBOF) / footprint 523 of 1140 (J18), pads 1-114 of 202")
	)
	(layers
		(0 "F.Cu" signal "TOP")
		(4 "In1.Cu" signal "L2GND")
		(6 "In2.Cu" signal "L3")
		(8 "In3.Cu" signal "L4VCC")
		(10 "In4.Cu" signal "L5VCC")
		(12 "In5.Cu" signal "L6")
		(14 "In6.Cu" signal "L7GND")
		(2 "B.Cu" signal "BOTTOM")
		(9 "F.Adhes" user "F.Adhesive")
		(11 "B.Adhes" user "B.Adhesive")
		(13 "F.Paste" user "Package Geometry/Pastemask Top")
		(15 "B.Paste" user "Package Geometry/Pastemask Bottom")
		(5 "F.SilkS" user "Ref Des/Silkscreen Top")
		(7 "B.SilkS" user "Ref Des/Silkscreen Bottom")
		(1 "F.Mask" user "Board Geometry/Soldermask Top")
		(3 "B.Mask" user "Board Geometry/Soldermask Bottom")
		(17 "Dwgs.User" user "User.Drawings")
		(19 "Cmts.User" user "User.Comments")
		(21 "Eco1.User" user "User.Eco1")
		(23 "Eco2.User" user "User.Eco2")
		(25 "Edge.Cuts" user "Board Geometry/Outline")
		(27 "Margin" user)
		(31 "F.CrtYd" user "Package Geometry/Place Bound Top")
		(29 "B.CrtYd" user "Package Geometry/Place Bound Bottom")
		(35 "F.Fab" user "Ref Des/Assembly Top")
		(33 "B.Fab" user "Ref Des/Assembly Bottom")
	)
	(footprint ""
		(layer "F.Cu")
		(at 2.999994 -319.14211 90)
		(property "Reference" "J18"
			(at 0 0 90)
			(layer "F.SilkS")
			(hide yes)
			(effects
				(font
					(size 1.27 1.27)
				)
			)
		)
		(property "Value" "PCISLT200-5-GP-U"
			(at -48.7045 -6.7818 90)
			(unlocked yes)
			(layer "F.Fab")
			(hide yes)
			(effects
				(font
					(size 1.016 1.016)
					(thickness 0.1524)
				)
			)
		)
		(property "Device Type" "G639F200221431HR-U"
			(at -48.7045 -8.3058 90)
			(unlocked yes)
			(layer "F.Fab")
			(hide yes)
			(effects
				(font
					(size 1.016 1.016)
					(thickness 0.1524)
				)
			)
		)
		(duplicate_pad_numbers_are_jumpers no)
		(pad "" np_thru_hole circle
			(at -47.999904 0 90)
			(size 0.254 0.254)
			(drill 2.2098)
			(layers "*.Cu" "*.Mask")
			(clearance 1.3335)
			(thermal_gap 1.3335)
		)
		(pad "" np_thru_hole circle
			(at 47.999904 0 90)
			(size 0.254 0.254)
			(drill 2.2098)
			(layers "*.Cu" "*.Mask")
			(clearance 1.3335)
			(thermal_gap 1.3335)
		)
		(pad "A1" smd rect
			(at -41.20007 -0.750062 90)
			(size 0.508 2.4892)
			(layers "F.Cu" "F.Mask" "F.Paste")
			(net "GND")
		)
		(pad "A2" smd rect
			(at -40.39997 -0.750062 90)
			(size 0.508 2.4892)
			(layers "F.Cu" "F.Mask" "F.Paste")
			(net "PE_TX3_DR4_N")
		)
		(pad "A3" smd rect
			(at -39.600124 -0.750062 90)
			(size 0.508 2.4892)
			(layers "F.Cu" "F.Mask" "F.Paste")
			(net "PE_TX3_DR4_P")
		)
		(pad "A4" smd rect
			(at -38.800024 -0.750062 90)
			(size 0.508 2.4892)
			(layers "F.Cu" "F.Mask" "F.Paste")
			(net "GND")
		)
		(pad "A5" smd rect
			(at -37.999924 -0.750062 90)
			(size 0.508 2.4892)
			(layers "F.Cu" "F.Mask" "F.Paste")
			(net "GND")
		)
		(pad "A6" smd rect
			(at -37.200078 -0.750062 90)
			(size 0.508 2.4892)
			(layers "F.Cu" "F.Mask" "F.Paste")
			(net "PE_TX4_DR4_N")
		)
		(pad "A7" smd rect
			(at -36.399978 -0.750062 90)
			(size 0.508 2.4892)
			(layers "F.Cu" "F.Mask" "F.Paste")
			(net "PE_TX4_DR4_P")
		)
		(pad "A8" smd rect
			(at -35.599878 -0.750062 90)
			(size 0.508 2.4892)
			(layers "F.Cu" "F.Mask" "F.Paste")
			(net "GND")
		)
		(pad "A9" smd rect
			(at -34.800032 -0.750062 90)
			(size 0.508 2.4892)
			(layers "F.Cu" "F.Mask" "F.Paste")
			(net "SSD3_PERST_N")
		)
		(pad "A10" smd rect
			(at -33.999932 -0.750062 90)
			(size 0.508 2.4892)
			(layers "F.Cu" "F.Mask" "F.Paste")
			(net "SSD3_PWREN")
		)
		(pad "A11" smd rect
			(at -33.200086 -0.750062 90)
			(size 0.508 2.4892)
			(layers "F.Cu" "F.Mask" "F.Paste")
			(net "ATTN_LED_DR3_N")
		)
		(pad "A12" smd rect
			(at -32.399986 -0.750062 90)
			(size 0.508 2.4892)
			(layers "F.Cu" "F.Mask" "F.Paste")
			(net "SSD3_CLK0_OE_R_N")
		)
		(pad "A13" smd rect
			(at -31.599886 -0.750062 90)
			(size 0.508 2.4892)
			(layers "F.Cu" "F.Mask" "F.Paste")
			(net "GND")
		)
		(pad "A14" smd rect
			(at -30.80004 -0.750062 90)
			(size 0.508 2.4892)
			(layers "F.Cu" "F.Mask" "F.Paste")
			(net "PE_TX1_DR3_N")
		)
		(pad "A15" smd rect
			(at -29.99994 -0.750062 90)
			(size 0.508 2.4892)
			(layers "F.Cu" "F.Mask" "F.Paste")
			(net "PE_TX1_DR3_P")
		)
		(pad "A16" smd rect
			(at -29.200094 -0.750062 90)
			(size 0.508 2.4892)
			(layers "F.Cu" "F.Mask" "F.Paste")
			(net "GND")
		)
		(pad "A17" smd rect
			(at -28.399994 -0.750062 90)
			(size 0.508 2.4892)
			(layers "F.Cu" "F.Mask" "F.Paste")
			(net "GND")
		)
		(pad "A18" smd rect
			(at -27.599894 -0.750062 90)
			(size 0.508 2.4892)
			(layers "F.Cu" "F.Mask" "F.Paste")
			(net "PE_TX2_DR3_N")
		)
		(pad "A19" smd rect
			(at -26.800048 -0.750062 90)
			(size 0.508 2.4892)
			(layers "F.Cu" "F.Mask" "F.Paste")
			(net "PE_TX2_DR3_P")
		)
		(pad "A20" smd rect
			(at -25.999948 -0.750062 90)
			(size 0.508 2.4892)
			(layers "F.Cu" "F.Mask" "F.Paste")
			(net "GND")
		)
		(pad "A21" smd rect
			(at -25.200102 -0.750062 90)
			(size 0.508 2.4892)
			(layers "F.Cu" "F.Mask" "F.Paste")
			(net "GND")
		)
		(pad "A22" smd rect
			(at -24.400002 -0.750062 90)
			(size 0.508 2.4892)
			(layers "F.Cu" "F.Mask" "F.Paste")
			(net "PE_TX3_DR3_N")
		)
		(pad "A23" smd rect
			(at -23.599902 -0.750062 90)
			(size 0.508 2.4892)
			(layers "F.Cu" "F.Mask" "F.Paste")
			(net "PE_TX3_DR3_P")
		)
		(pad "A24" smd rect
			(at -22.800056 -0.750062 90)
			(size 0.508 2.4892)
			(layers "F.Cu" "F.Mask" "F.Paste")
			(net "GND")
		)
		(pad "A25" smd rect
			(at -21.999956 -0.750062 90)
			(size 0.508 2.4892)
			(layers "F.Cu" "F.Mask" "F.Paste")
			(net "GND")
		)
		(pad "A26" smd rect
			(at -21.20011 -0.750062 90)
			(size 0.508 2.4892)
			(layers "F.Cu" "F.Mask" "F.Paste")
			(net "PE_TX4_DR3_N")
		)
		(pad "A27" smd rect
			(at -20.40001 -0.750062 90)
			(size 0.508 2.4892)
			(layers "F.Cu" "F.Mask" "F.Paste")
			(net "PE_TX4_DR3_P")
		)
		(pad "A28" smd rect
			(at -19.59991 -0.750062 90)
			(size 0.508 2.4892)
			(layers "F.Cu" "F.Mask" "F.Paste")
			(net "GND")
		)
		(pad "A29" smd rect
			(at -18.800064 -0.750062 90)
			(size 0.508 2.4892)
			(layers "F.Cu" "F.Mask" "F.Paste")
			(net "GND")
		)
		(pad "A30" smd rect
			(at -17.999964 -0.750062 90)
			(size 0.508 2.4892)
			(layers "F.Cu" "F.Mask" "F.Paste")
			(net "PE_TX1_DR7_N")
		)
		(pad "A31" smd rect
			(at -17.200118 -0.750062 90)
			(size 0.508 2.4892)
			(layers "F.Cu" "F.Mask" "F.Paste")
			(net "PE_TX1_DR7_P")
		)
		(pad "A32" smd rect
			(at -16.400018 -0.750062 90)
			(size 0.508 2.4892)
			(layers "F.Cu" "F.Mask" "F.Paste")
			(net "GND")
		)
		(pad "A33" smd rect
			(at -15.599918 -0.750062 90)
			(size 0.508 2.4892)
			(layers "F.Cu" "F.Mask" "F.Paste")
			(net "GND")
		)
		(pad "A34" smd rect
			(at -14.800072 -0.750062 90)
			(size 0.508 2.4892)
			(layers "F.Cu" "F.Mask" "F.Paste")
			(net "PE_TX2_DR7_N")
		)
		(pad "A35" smd rect
			(at -13.999972 -0.750062 90)
			(size 0.508 2.4892)
			(layers "F.Cu" "F.Mask" "F.Paste")
			(net "PE_TX2_DR7_P")
		)
		(pad "A36" smd rect
			(at -13.200126 -0.750062 90)
			(size 0.508 2.4892)
			(layers "F.Cu" "F.Mask" "F.Paste")
			(net "GND")
		)
		(pad "A37" smd rect
			(at -12.400026 -0.750062 90)
			(size 0.508 2.4892)
			(layers "F.Cu" "F.Mask" "F.Paste")
			(net "GND")
		)
		(pad "A38" smd rect
			(at -11.599926 -0.750062 90)
			(size 0.508 2.4892)
			(layers "F.Cu" "F.Mask" "F.Paste")
			(net "PE_TX3_DR7_N")
		)
		(pad "A39" smd rect
			(at -10.80008 -0.750062 90)
			(size 0.508 2.4892)
			(layers "F.Cu" "F.Mask" "F.Paste")
			(net "PE_TX3_DR7_P")
		)
		(pad "A40" smd rect
			(at -9.99998 -0.750062 90)
			(size 0.508 2.4892)
			(layers "F.Cu" "F.Mask" "F.Paste")
			(net "GND")
		)
		(pad "A41" smd rect
			(at -9.19988 -0.750062 90)
			(size 0.508 2.4892)
			(layers "F.Cu" "F.Mask" "F.Paste")
			(net "GND")
		)
		(pad "A42" smd rect
			(at -8.400034 -0.750062 90)
			(size 0.508 2.4892)
			(layers "F.Cu" "F.Mask" "F.Paste")
			(net "PE_TX4_DR7_N")
		)
		(pad "A43" smd rect
			(at -7.599934 -0.750062 90)
			(size 0.508 2.4892)
			(layers "F.Cu" "F.Mask" "F.Paste")
			(net "PE_TX4_DR7_P")
		)
		(pad "A44" smd rect
			(at -6.800088 -0.750062 90)
			(size 0.508 2.4892)
			(layers "F.Cu" "F.Mask" "F.Paste")
			(net "GND")
		)
		(pad "A45" smd rect
			(at -2.800096 -0.750062 90)
			(size 0.508 2.4892)
			(layers "F.Cu" "F.Mask" "F.Paste")
			(net "ATTN_LED_DR7_N")
		)
		(pad "A46" smd rect
			(at -1.999996 -0.750062 90)
			(size 0.508 2.4892)
			(layers "F.Cu" "F.Mask" "F.Paste")
			(net "SSD7_CLK0_OE_R_N")
		)
		(pad "A47" smd rect
			(at -1.199896 -0.750062 90)
			(size 0.508 2.4892)
			(layers "F.Cu" "F.Mask" "F.Paste")
			(net "GND")
		)
		(pad "A48" smd rect
			(at -0.40005 -0.750062 90)
			(size 0.508 2.4892)
			(layers "F.Cu" "F.Mask" "F.Paste")
			(net "PE_TX1_DR2_N")
		)
		(pad "A49" smd rect
			(at 0.40005 -0.750062 90)
			(size 0.508 2.4892)
			(layers "F.Cu" "F.Mask" "F.Paste")
			(net "PE_TX1_DR2_P")
		)
		(pad "A50" smd rect
			(at 1.199896 -0.750062 90)
			(size 0.508 2.4892)
			(layers "F.Cu" "F.Mask" "F.Paste")
			(net "GND")
		)
		(pad "A51" smd rect
			(at 1.999996 -0.750062 90)
			(size 0.508 2.4892)
			(layers "F.Cu" "F.Mask" "F.Paste")
			(net "GND")
		)
		(pad "A52" smd rect
			(at 2.800096 -0.750062 90)
			(size 0.508 2.4892)
			(layers "F.Cu" "F.Mask" "F.Paste")
			(net "PE_TX2_DR2_N")
		)
		(pad "A53" smd rect
			(at 3.599942 -0.750062 90)
			(size 0.508 2.4892)
			(layers "F.Cu" "F.Mask" "F.Paste")
			(net "PE_TX2_DR2_P")
		)
		(pad "A54" smd rect
			(at 4.400042 -0.750062 90)
			(size 0.508 2.4892)
			(layers "F.Cu" "F.Mask" "F.Paste")
			(net "GND")
		)
		(pad "A55" smd rect
			(at 5.199888 -0.750062 90)
			(size 0.508 2.4892)
			(layers "F.Cu" "F.Mask" "F.Paste")
			(net "GND")
		)
		(pad "A56" smd rect
			(at 5.999988 -0.750062 90)
			(size 0.508 2.4892)
			(layers "F.Cu" "F.Mask" "F.Paste")
			(net "PE_TX3_DR2_N")
		)
		(pad "A57" smd rect
			(at 6.800088 -0.750062 90)
			(size 0.508 2.4892)
			(layers "F.Cu" "F.Mask" "F.Paste")
			(net "PE_TX3_DR2_P")
		)
		(pad "A58" smd rect
			(at 7.599934 -0.750062 90)
			(size 0.508 2.4892)
			(layers "F.Cu" "F.Mask" "F.Paste")
			(net "GND")
		)
		(pad "A59" smd rect
			(at 8.400034 -0.750062 90)
			(size 0.508 2.4892)
			(layers "F.Cu" "F.Mask" "F.Paste")
			(net "GND")
		)
		(pad "A60" smd rect
			(at 9.19988 -0.750062 90)
			(size 0.508 2.4892)
			(layers "F.Cu" "F.Mask" "F.Paste")
			(net "PE_TX4_DR2_N")
		)
		(pad "A61" smd rect
			(at 9.99998 -0.750062 90)
			(size 0.508 2.4892)
			(layers "F.Cu" "F.Mask" "F.Paste")
			(net "PE_TX4_DR2_P")
		)
		(pad "A62" smd rect
			(at 10.80008 -0.750062 90)
			(size 0.508 2.4892)
			(layers "F.Cu" "F.Mask" "F.Paste")
			(net "GND")
		)
		(pad "A63" smd rect
			(at 11.599926 -0.750062 90)
			(size 0.508 2.4892)
			(layers "F.Cu" "F.Mask" "F.Paste")
			(net "SSD2_PWREN")
		)
		(pad "A64" smd rect
			(at 12.400026 -0.750062 90)
			(size 0.508 2.4892)
			(layers "F.Cu" "F.Mask" "F.Paste")
			(net "ATTN_LED_DR2_N")
		)
		(pad "A65" smd rect
			(at 13.200126 -0.750062 90)
			(size 0.508 2.4892)
			(layers "F.Cu" "F.Mask" "F.Paste")
			(net "SSD2_CLK0_OE_R_N")
		)
		(pad "A66" smd rect
			(at 13.999972 -0.750062 90)
			(size 0.508 2.4892)
			(layers "F.Cu" "F.Mask" "F.Paste")
			(net "GND")
		)
		(pad "A67" smd rect
			(at 14.800072 -0.750062 90)
			(size 0.508 2.4892)
			(layers "F.Cu" "F.Mask" "F.Paste")
			(net "PE_TX1_DR11_N")
		)
		(pad "A68" smd rect
			(at 15.599918 -0.750062 90)
			(size 0.508 2.4892)
			(layers "F.Cu" "F.Mask" "F.Paste")
			(net "PE_TX1_DR11_P")
		)
		(pad "A69" smd rect
			(at 16.400018 -0.750062 90)
			(size 0.508 2.4892)
			(layers "F.Cu" "F.Mask" "F.Paste")
			(net "GND")
		)
		(pad "A70" smd rect
			(at 17.200118 -0.750062 90)
			(size 0.508 2.4892)
			(layers "F.Cu" "F.Mask" "F.Paste")
			(net "GND")
		)
		(pad "A71" smd rect
			(at 17.999964 -0.750062 90)
			(size 0.508 2.4892)
			(layers "F.Cu" "F.Mask" "F.Paste")
			(net "PE_TX2_DR11_N")
		)
		(pad "A72" smd rect
			(at 18.800064 -0.750062 90)
			(size 0.508 2.4892)
			(layers "F.Cu" "F.Mask" "F.Paste")
			(net "PE_TX2_DR11_P")
		)
		(pad "A73" smd rect
			(at 19.59991 -0.750062 90)
			(size 0.508 2.4892)
			(layers "F.Cu" "F.Mask" "F.Paste")
			(net "GND")
		)
		(pad "A74" smd rect
			(at 20.40001 -0.750062 90)
			(size 0.508 2.4892)
			(layers "F.Cu" "F.Mask" "F.Paste")
			(net "GND")
		)
		(pad "A75" smd rect
			(at 21.20011 -0.750062 90)
			(size 0.508 2.4892)
			(layers "F.Cu" "F.Mask" "F.Paste")
			(net "PE_TX3_DR11_N")
		)
		(pad "A76" smd rect
			(at 21.999956 -0.750062 90)
			(size 0.508 2.4892)
			(layers "F.Cu" "F.Mask" "F.Paste")
			(net "PE_TX3_DR11_P")
		)
		(pad "A77" smd rect
			(at 22.800056 -0.750062 90)
			(size 0.508 2.4892)
			(layers "F.Cu" "F.Mask" "F.Paste")
			(net "GND")
		)
		(pad "A78" smd rect
			(at 23.599902 -0.750062 90)
			(size 0.508 2.4892)
			(layers "F.Cu" "F.Mask" "F.Paste")
			(net "GND")
		)
		(pad "A79" smd rect
			(at 24.400002 -0.750062 90)
			(size 0.508 2.4892)
			(layers "F.Cu" "F.Mask" "F.Paste")
			(net "PE_TX4_DR11_N")
		)
		(pad "A80" smd rect
			(at 25.200102 -0.750062 90)
			(size 0.508 2.4892)
			(layers "F.Cu" "F.Mask" "F.Paste")
			(net "PE_TX4_DR11_P")
		)
		(pad "A81" smd rect
			(at 25.999948 -0.750062 90)
			(size 0.508 2.4892)
			(layers "F.Cu" "F.Mask" "F.Paste")
			(net "GND")
		)
		(pad "A82" smd rect
			(at 26.800048 -0.750062 90)
			(size 0.508 2.4892)
			(layers "F.Cu" "F.Mask" "F.Paste")
			(net "GND")
		)
		(pad "A83" smd rect
			(at 27.599894 -0.750062 90)
			(size 0.508 2.4892)
			(layers "F.Cu" "F.Mask" "F.Paste")
			(net "PE_TX1_DR6_N")
		)
		(pad "A84" smd rect
			(at 28.399994 -0.750062 90)
			(size 0.508 2.4892)
			(layers "F.Cu" "F.Mask" "F.Paste")
			(net "PE_TX1_DR6_P")
		)
		(pad "A85" smd rect
			(at 29.200094 -0.750062 90)
			(size 0.508 2.4892)
			(layers "F.Cu" "F.Mask" "F.Paste")
			(net "GND")
		)
		(pad "A86" smd rect
			(at 29.99994 -0.750062 90)
			(size 0.508 2.4892)
			(layers "F.Cu" "F.Mask" "F.Paste")
			(net "GND")
		)
		(pad "A87" smd rect
			(at 30.80004 -0.750062 90)
			(size 0.508 2.4892)
			(layers "F.Cu" "F.Mask" "F.Paste")
			(net "PE_TX2_DR6_N")
		)
		(pad "A88" smd rect
			(at 31.599886 -0.750062 90)
			(size 0.508 2.4892)
			(layers "F.Cu" "F.Mask" "F.Paste")
			(net "PE_TX2_DR6_P")
		)
		(pad "A89" smd rect
			(at 32.399986 -0.750062 90)
			(size 0.508 2.4892)
			(layers "F.Cu" "F.Mask" "F.Paste")
			(net "GND")
		)
		(pad "A90" smd rect
			(at 33.200086 -0.750062 90)
			(size 0.508 2.4892)
			(layers "F.Cu" "F.Mask" "F.Paste")
			(net "GND")
		)
		(pad "A91" smd rect
			(at 33.999932 -0.750062 90)
			(size 0.508 2.4892)
			(layers "F.Cu" "F.Mask" "F.Paste")
			(net "PE_TX3_DR6_N")
		)
		(pad "A92" smd rect
			(at 34.800032 -0.750062 90)
			(size 0.508 2.4892)
			(layers "F.Cu" "F.Mask" "F.Paste")
			(net "PE_TX3_DR6_P")
		)
		(pad "A93" smd rect
			(at 35.599878 -0.750062 90)
			(size 0.508 2.4892)
			(layers "F.Cu" "F.Mask" "F.Paste")
			(net "GND")
		)
		(pad "A94" smd rect
			(at 36.399978 -0.750062 90)
			(size 0.508 2.4892)
			(layers "F.Cu" "F.Mask" "F.Paste")
			(net "GND")
		)
		(pad "A95" smd rect
			(at 37.200078 -0.750062 90)
			(size 0.508 2.4892)
			(layers "F.Cu" "F.Mask" "F.Paste")
			(net "PE_TX4_DR6_N")
		)
		(pad "A96" smd rect
			(at 37.999924 -0.750062 90)
			(size 0.508 2.4892)
			(layers "F.Cu" "F.Mask" "F.Paste")
			(net "PE_TX4_DR6_P")
		)
		(pad "A97" smd rect
			(at 38.800024 -0.750062 90)
			(size 0.508 2.4892)
			(layers "F.Cu" "F.Mask" "F.Paste")
			(net "GND")
		)
		(pad "A98" smd rect
			(at 39.600124 -0.750062 90)
			(size 0.508 2.4892)
			(layers "F.Cu" "F.Mask" "F.Paste")
			(net "SSD6_CLK0_OE_R_N")
		)
		(pad "A99" smd rect
			(at 40.39997 -0.750062 90)
			(size 0.508 2.4892)
			(layers "F.Cu" "F.Mask" "F.Paste")
			(net "ATTN_LED_DR6_N")
		)
		(pad "A100" smd rect
			(at 41.20007 -0.750062 90)
			(size 0.508 2.4892)
			(layers "F.Cu" "F.Mask" "F.Paste")
			(net "SSD6_PWREN")
		)
		(pad "B1" smd rect
			(at -41.20007 -1.131062 90)
			(size 0.508 2.4892)
			(drill
				(offset 0 0.381)
			)
			(layers "F.Cu" "F.Mask" "F.Paste")
			(net "SSD11_PERST_N")
		)
		(pad "B2" smd rect
			(at -40.39997 -1.131062 90)
			(size 0.508 2.4892)
			(drill
				(offset 0 0.381)
			)
			(layers "F.Cu" "F.Mask" "F.Paste")
			(net "SSD2_PERST_N")
		)
		(pad "B3" smd rect
			(at -39.600124 -1.131062 90)
			(size 0.508 2.4892)
			(drill
				(offset 0 0.381)
			)
			(layers "F.Cu" "F.Mask" "F.Paste")
			(net "GND")
		)
		(pad "B4" smd rect
			(at -38.800024 -1.131062 90)
			(size 0.508 2.4892)
			(drill
				(offset 0 0.381)
			)
			(layers "F.Cu" "F.Mask" "F.Paste")
			(net "PE_RX3_DR4_N")
		)
		(pad "B5" smd rect
			(at -37.999924 -1.131062 90)
			(size 0.508 2.4892)
			(drill
				(offset 0 0.381)
			)
			(layers "F.Cu" "F.Mask" "F.Paste")
			(net "PE_RX3_DR4_P")
		)
		(pad "B6" smd rect
			(at -37.200078 -1.131062 90)
			(size 0.508 2.4892)
			(drill
				(offset 0 0.381)
			)
			(layers "F.Cu" "F.Mask" "F.Paste")
			(net "GND")
		)
		(pad "B7" smd rect
			(at -36.399978 -1.131062 90)
			(size 0.508 2.4892)
			(drill
				(offset 0 0.381)
			)
			(layers "F.Cu" "F.Mask" "F.Paste")
			(net "GND")
		)
		(pad "B8" smd rect
			(at -35.599878 -1.131062 90)
			(size 0.508 2.4892)
			(drill
				(offset 0 0.381)
			)
			(layers "F.Cu" "F.Mask" "F.Paste")
			(net "PE_RX4_DR4_N")
		)
		(pad "B9" smd rect
			(at -34.800032 -1.131062 90)
			(size 0.508 2.4892)
			(drill
				(offset 0 0.381)
			)
			(layers "F.Cu" "F.Mask" "F.Paste")
			(net "PE_RX4_DR4_P")
		)
		(pad "B10" smd rect
			(at -33.999932 -1.131062 90)
			(size 0.508 2.4892)
			(drill
				(offset 0 0.381)
			)
			(layers "F.Cu" "F.Mask" "F.Paste")
			(net "GND")
		)
		(pad "B11" smd rect
			(at -33.200086 -1.131062 90)
			(size 0.508 2.4892)
			(drill
				(offset 0 0.381)
			)
			(layers "F.Cu" "F.Mask" "F.Paste")
			(net "SSD12_PERST_N")
		)
		(pad "B12" smd rect
			(at -32.399986 -1.131062 90)
			(size 0.508 2.4892)
			(drill
				(offset 0 0.381)
			)
			(layers "F.Cu" "F.Mask" "F.Paste")
			(net "SSD12_PWREN")
		)
	)
)
